(kicad_pcb
	(version 20260206)
	(generator "pcbnew")
	(generator_version "10.0")
	(general
		(thickness 1.6)
		(legacy_teardrops no)
	)
	(paper "A4")
	(title_block
		(title "Bryce Canyon_SCC_16316-1_OCP.brd")
		(comment 1 "Bryce Canyon / footprints 1395-1398 of 1561")
	)
	(layers
		(0 "F.Cu" signal "TOP")
		(4 "In1.Cu" signal "L2GND")
		(6 "In2.Cu" signal "L3")
		(8 "In3.Cu" signal "L4VCC")
		(10 "In4.Cu" signal "L5VCC")
		(12 "In5.Cu" signal "L6")
		(14 "In6.Cu" signal "L7GND")
		(2 "B.Cu" signal "BOTTOM")
		(9 "F.Adhes" user "F.Adhesive")
		(11 "B.Adhes" user "B.Adhesive")
		(13 "F.Paste" user "Package Geometry/Pastemask Top")
		(15 "B.Paste" user "Package Geometry/Pastemask Bottom")
		(5 "F.SilkS" user "Ref Des/Silkscreen Top")
		(7 "B.SilkS" user "Ref Des/Silkscreen Bottom")
		(1 "F.Mask" user "Board Geometry/Soldermask Top")
		(3 "B.Mask" user "Board Geometry/Soldermask Bottom")
		(17 "Dwgs.User" user "User.Drawings")
		(19 "Cmts.User" user "User.Comments")
		(21 "Eco1.User" user "User.Eco1")
		(23 "Eco2.User" user "User.Eco2")
		(25 "Edge.Cuts" user "Board Geometry/Outline")
		(27 "Margin" user)
		(31 "F.CrtYd" user "Package Geometry/Place Bound Top")
		(29 "B.CrtYd" user "Package Geometry/Place Bound Bottom")
		(35 "F.Fab" user "Ref Des/Assembly Top")
		(33 "B.Fab" user "Ref Des/Assembly Bottom")
	)
	(footprint ""
		(layer "B.Cu")
		(at 70.485 -39.751 90)
		(property "Reference" "L17"
			(at 0 0 90)
			(layer "B.SilkS")
			(hide yes)
			(effects
				(font
					(size 1.27 1.27)
				)
				(justify mirror)
			)
		)
		(property "Value" "MPZ2012S300AT-GP"
			(at 0 -4.2418 90)
			(unlocked yes)
			(layer "B.Fab")
			(hide yes)
			(effects
				(font
					(size 1.016 1.016)
					(thickness 0.1524)
				)
				(justify mirror)
			)
		)
		(property "Device Type" "L805H42"
			(at 0 -5.7912 90)
			(unlocked yes)
			(layer "B.Fab")
			(hide yes)
			(effects
				(font
					(size 1.016 1.016)
					(thickness 0.1524)
				)
				(justify mirror)
			)
		)
		(duplicate_pad_numbers_are_jumpers no)
		(fp_line
			(start 0.889 -1.7018)
			(end -0.889 -1.7018)
			(stroke
				(width 0.1524)
				(type default)
			)
			(layer "B.SilkS")
		)
		(fp_line
			(start -0.889 -1.7018)
			(end -0.889 1.7018)
			(stroke
				(width 0.1524)
				(type default)
			)
			(layer "B.SilkS")
		)
		(fp_line
			(start 0.889 1.7018)
			(end 0.889 -1.7018)
			(stroke
				(width 0.1524)
				(type default)
			)
			(layer "B.SilkS")
		)
		(fp_line
			(start -0.889 1.7018)
			(end 0.889 1.7018)
			(stroke
				(width 0.1524)
				(type default)
			)
			(layer "B.SilkS")
		)
		(fp_rect
			(start 0.9652 1.778)
			(end -0.9652 -1.778)
			(stroke
				(width 0)
				(type default)
			)
			(fill no)
			(layer "B.CrtYd")
		)
		(fp_rect
			(start 0.9652 1.778)
			(end -0.9652 -1.778)
			(stroke
				(width 0)
				(type default)
			)
			(fill no)
			(layer "B.Fab")
		)
		(pad "1" smd rect
			(at 0 -0.9652 270)
			(size 1.397 1.143)
			(layers "B.Cu" "B.Mask" "B.Paste")
			(net "P0V9")
		)
		(pad "2" smd rect
			(at 0 0.9652 270)
			(size 1.397 1.143)
			(layers "B.Cu" "B.Mask" "B.Paste")
			(net "GB_VDDA")
		)
	)
	(footprint ""
		(layer "B.Cu")
		(at 134.493254 -64.507618 -90)
		(property "Reference" "C22"
			(at 0 0 90)
			(layer "B.SilkS")
			(hide yes)
			(effects
				(font
					(size 1.27 1.27)
				)
				(justify mirror)
			)
		)
		(property "Value" "SCD01U16V1KX-GP"
			(at 2.8321 -1.7399 270)
			(unlocked yes)
			(layer "B.Fab")
			(hide yes)
			(effects
				(font
					(size 1.016 1.016)
					(thickness 0.1524)
				)
				(justify mirror)
			)
		)
		(property "Device Type" "C0201H13"
			(at 2.8321 -3.2639 270)
			(unlocked yes)
			(layer "B.Fab")
			(hide yes)
			(effects
				(font
					(size 1.016 1.016)
					(thickness 0.1524)
				)
				(justify mirror)
			)
		)
		(duplicate_pad_numbers_are_jumpers no)
		(fp_rect
			(start 0.2794 0.6477)
			(end -0.2794 -0.6477)
			(stroke
				(width 0)
				(type default)
			)
			(fill no)
			(layer "B.CrtYd")
		)
		(fp_rect
			(start 0.2794 0.6477)
			(end -0.2794 -0.6477)
			(stroke
				(width 0)
				(type default)
			)
			(fill no)
			(layer "B.Fab")
		)
		(pad "1" smd custom
			(at 0 -0.2794 90)
			(size 0.0762 0.0762)
			(layers "B.Cu" "B.Mask" "B.Paste")
			(net "PHY_DPB_TO_SCC_1_DN")
			(options
				(clearance outline)
				(anchor circle)
			)
			(primitives
				(gr_poly
					(pts
						(arc
							(start 0.1524 0.127)
							(mid 0.137521 0.162921)
							(end 0.1016 0.1778)
						)
						(arc
							(start -0.1016 0.1778)
							(mid -0.137521 0.162921)
							(end -0.1524 0.127)
						)
						(arc
							(start -0.1524 -0.127)
							(mid -0.137521 -0.162921)
							(end -0.1016 -0.1778)
						)
						(arc
							(start 0.1016 -0.1778)
							(mid 0.137521 -0.162921)
							(end 0.1524 -0.127)
						)
					)
					(width 0)
					(fill yes)
				)
			)
		)
		(pad "2" smd custom
			(at 0 0.2794 90)
			(size 0.0762 0.0762)
			(layers "B.Cu" "B.Mask" "B.Paste")
			(net "PHY_DPB_TO_SCC_C_1_DN")
			(options
				(clearance outline)
				(anchor circle)
			)
			(primitives
				(gr_poly
					(pts
						(arc
							(start 0.1524 0.127)
							(mid 0.137521 0.162921)
							(end 0.1016 0.1778)
						)
						(arc
							(start -0.1016 0.1778)
							(mid -0.137521 0.162921)
							(end -0.1524 0.127)
						)
						(arc
							(start -0.1524 -0.127)
							(mid -0.137521 -0.162921)
							(end -0.1016 -0.1778)
						)
						(arc
							(start 0.1016 -0.1778)
							(mid 0.137521 -0.162921)
							(end 0.1524 -0.127)
						)
					)
					(width 0)
					(fill yes)
				)
			)
		)
	)
	(footprint ""
		(layer "B.Cu")
		(at 80.518 -85.217 180)
		(property "Reference" "U13"
			(at 0 0 0)
			(layer "B.SilkS")
			(hide yes)
			(effects
				(font
					(size 1.27 1.27)
				)
				(justify mirror)
			)
		)
		(property "Value" "S29GL128S10TFIV20-GP"
			(at 0.1778 -20.32 180)
			(unlocked yes)
			(layer "B.Fab")
			(hide yes)
			(effects
				(font
					(size 1.016 1.016)
					(thickness 0.1524)
				)
				(justify mirror)
			)
		)
		(property "Device Type" "TSOP56-1H48"
			(at 0.1778 -22.225 180)
			(unlocked yes)
			(layer "B.Fab")
			(hide yes)
			(effects
				(font
					(size 1.016 1.016)
					(thickness 0.1524)
				)
				(justify mirror)
			)
		)
		(duplicate_pad_numbers_are_jumpers no)
		(fp_line
			(start 7.5438 8.5598)
			(end -6.8326 8.5598)
			(stroke
				(width 0.1524)
				(type default)
			)
			(layer "B.SilkS")
		)
		(fp_line
			(start 7.5438 -0.4318)
			(end 7.112 0)
			(stroke
				(width 0.1524)
				(type default)
			)
			(layer "B.SilkS")
		)
		(fp_line
			(start 7.5438 -8.5598)
			(end 7.5438 8.5598)
			(stroke
				(width 0.1524)
				(type default)
			)
			(layer "B.SilkS")
		)
		(fp_line
			(start 7.366 8.5598)
			(end 7.366 10.795)
			(stroke
				(width 0.508)
				(type default)
			)
			(layer "B.SilkS")
		)
		(fp_line
			(start 7.112 0)
			(end 7.5438 0.4318)
			(stroke
				(width 0.1524)
				(type default)
			)
			(layer "B.SilkS")
		)
		(fp_line
			(start -6.8326 8.5598)
			(end -6.8326 -8.5598)
			(stroke
				(width 0.1524)
				(type default)
			)
			(layer "B.SilkS")
		)
		(fp_line
			(start -6.8326 -8.5598)
			(end 7.5438 -8.5598)
			(stroke
				(width 0.1524)
				(type default)
			)
			(layer "B.SilkS")
		)
		(fp_poly
			(pts
				(xy 7.62 11.049) (xy -7.62 11.049) (xy -7.62 -11.049) (xy 7.62 -11.049)
			)
			(stroke
				(width 0)
				(type default)
			)
			(fill no)
			(layer "B.CrtYd")
		)
		(fp_poly
			(pts
				(xy 7.62 -11.049) (xy -7.62 -11.049) (xy -7.62 11.049) (xy 7.62 11.049)
			)
			(stroke
				(width 0)
				(type default)
			)
			(fill no)
			(layer "B.Fab")
		)
		(pad "1" smd rect
			(at 6.75005 9.6139)
			(size 0.3048 1.524)
			(layers "B.Cu" "B.Mask" "B.Paste")
			(net "Net_772")
		)
		(pad "2" smd rect
			(at 6.24967 9.6139)
			(size 0.3048 1.524)
			(layers "B.Cu" "B.Mask" "B.Paste")
			(net "EXP_XM_ADDR_23")
		)
		(pad "3" smd rect
			(at 5.75056 9.6139)
			(size 0.3048 1.524)
			(layers "B.Cu" "B.Mask" "B.Paste")
			(net "EXP_XM_ADDR_16")
		)
		(pad "4" smd rect
			(at 5.25018 9.6139)
			(size 0.3048 1.524)
			(layers "B.Cu" "B.Mask" "B.Paste")
			(net "EXP_XM_ADDR_15")
		)
		(pad "5" smd rect
			(at 4.7498 9.6139)
			(size 0.3048 1.524)
			(layers "B.Cu" "B.Mask" "B.Paste")
			(net "EXP_XM_ADDR_14")
		)
		(pad "6" smd rect
			(at 4.24942 9.6139)
			(size 0.3048 1.524)
			(layers "B.Cu" "B.Mask" "B.Paste")
			(net "EXP_XM_ADDR_13")
		)
		(pad "7" smd rect
			(at 3.75031 9.6139)
			(size 0.3048 1.524)
			(layers "B.Cu" "B.Mask" "B.Paste")
			(net "EXP_XM_ADDR_12")
		)
		(pad "8" smd rect
			(at 3.24993 9.6139)
			(size 0.3048 1.524)
			(layers "B.Cu" "B.Mask" "B.Paste")
			(net "EXP_XM_ADDR_11")
		)
		(pad "9" smd rect
			(at 2.74955 9.6139)
			(size 0.3048 1.524)
			(layers "B.Cu" "B.Mask" "B.Paste")
			(net "EXP_XM_ADDR_10")
		)
		(pad "10" smd rect
			(at 2.25044 9.6139)
			(size 0.3048 1.524)
			(layers "B.Cu" "B.Mask" "B.Paste")
			(net "EXP_XM_ADDR_9")
		)
		(pad "11" smd rect
			(at 1.75006 9.6139)
			(size 0.3048 1.524)
			(layers "B.Cu" "B.Mask" "B.Paste")
			(net "EXP_XM_ADDR_20")
		)
		(pad "12" smd rect
			(at 1.24968 9.6139)
			(size 0.3048 1.524)
			(layers "B.Cu" "B.Mask" "B.Paste")
			(net "EXP_XM_ADDR_21")
		)
		(pad "13" smd rect
			(at 0.75057 9.6139)
			(size 0.3048 1.524)
			(layers "B.Cu" "B.Mask" "B.Paste")
			(net "EXP_XM_WE_N")
		)
		(pad "14" smd rect
			(at 0.25019 9.6139)
			(size 0.3048 1.524)
			(layers "B.Cu" "B.Mask" "B.Paste")
			(net "FW_RESET_N")
		)
		(pad "15" smd rect
			(at -0.25019 9.6139)
			(size 0.3048 1.524)
			(layers "B.Cu" "B.Mask" "B.Paste")
			(net "EXP_XM_ADDR_22")
		)
		(pad "16" smd rect
			(at -0.75057 9.6139)
			(size 0.3048 1.524)
			(layers "B.Cu" "B.Mask" "B.Paste")
			(net "EXP_WP_N")
		)
		(pad "17" smd rect
			(at -1.24968 9.6139)
			(size 0.3048 1.524)
			(layers "B.Cu" "B.Mask" "B.Paste")
			(net "EXP_XM_BUSY_N")
		)
		(pad "18" smd rect
			(at -1.75006 9.6139)
			(size 0.3048 1.524)
			(layers "B.Cu" "B.Mask" "B.Paste")
			(net "EXP_XM_ADDR_19")
		)
		(pad "19" smd rect
			(at -2.25044 9.6139)
			(size 0.3048 1.524)
			(layers "B.Cu" "B.Mask" "B.Paste")
			(net "EXP_XM_ADDR_18")
		)
		(pad "20" smd rect
			(at -2.74955 9.6139)
			(size 0.3048 1.524)
			(layers "B.Cu" "B.Mask" "B.Paste")
			(net "EXP_XM_ADDR_8")
		)
		(pad "21" smd rect
			(at -3.24993 9.6139)
			(size 0.3048 1.524)
			(layers "B.Cu" "B.Mask" "B.Paste")
			(net "EXP_XM_ADDR_7")
		)
		(pad "22" smd rect
			(at -3.75031 9.6139)
			(size 0.3048 1.524)
			(layers "B.Cu" "B.Mask" "B.Paste")
			(net "EXP_XM_ADDR_6")
		)
		(pad "23" smd rect
			(at -4.24942 9.6139)
			(size 0.3048 1.524)
			(layers "B.Cu" "B.Mask" "B.Paste")
			(net "EXP_XM_ADDR_5")
		)
		(pad "24" smd rect
			(at -4.7498 9.6139)
			(size 0.3048 1.524)
			(layers "B.Cu" "B.Mask" "B.Paste")
			(net "EXP_XM_ADDR_4")
		)
		(pad "25" smd rect
			(at -5.25018 9.6139)
			(size 0.3048 1.524)
			(layers "B.Cu" "B.Mask" "B.Paste")
			(net "EXP_XM_ADDR_3")
		)
		(pad "26" smd rect
			(at -5.75056 9.6139)
			(size 0.3048 1.524)
			(layers "B.Cu" "B.Mask" "B.Paste")
			(net "EXP_XM_ADDR_2")
		)
		(pad "27" smd rect
			(at -6.24967 9.6139)
			(size 0.3048 1.524)
			(layers "B.Cu" "B.Mask" "B.Paste")
			(net "Net_768")
		)
		(pad "28" smd rect
			(at -6.75005 9.6139)
			(size 0.3048 1.524)
			(layers "B.Cu" "B.Mask" "B.Paste")
			(net "Net_769")
		)
		(pad "29" smd rect
			(at -6.75005 -9.6139)
			(size 0.3048 1.524)
			(layers "B.Cu" "B.Mask" "B.Paste")
			(net "P1V8_E")
		)
		(pad "30" smd rect
			(at -6.24967 -9.6139)
			(size 0.3048 1.524)
			(layers "B.Cu" "B.Mask" "B.Paste")
			(net "Net_767")
		)
		(pad "31" smd rect
			(at -5.75056 -9.6139)
			(size 0.3048 1.524)
			(layers "B.Cu" "B.Mask" "B.Paste")
			(net "EXP_XM_ADDR_1")
		)
		(pad "32" smd rect
			(at -5.25018 -9.6139)
			(size 0.3048 1.524)
			(layers "B.Cu" "B.Mask" "B.Paste")
			(net "EXP_XM_NOR_CS_N")
		)
		(pad "33" smd rect
			(at -4.7498 -9.6139)
			(size 0.3048 1.524)
			(layers "B.Cu" "B.Mask" "B.Paste")
			(net "GND")
		)
		(pad "34" smd rect
			(at -4.24942 -9.6139)
			(size 0.3048 1.524)
			(layers "B.Cu" "B.Mask" "B.Paste")
			(net "EXP_XM_OE_N")
		)
		(pad "35" smd rect
			(at -3.75031 -9.6139)
			(size 0.3048 1.524)
			(layers "B.Cu" "B.Mask" "B.Paste")
			(net "XM_DATA0")
		)
		(pad "36" smd rect
			(at -3.24993 -9.6139)
			(size 0.3048 1.524)
			(layers "B.Cu" "B.Mask" "B.Paste")
			(net "XM_DATA8")
		)
		(pad "37" smd rect
			(at -2.74955 -9.6139)
			(size 0.3048 1.524)
			(layers "B.Cu" "B.Mask" "B.Paste")
			(net "XM_DATA1")
		)
		(pad "38" smd rect
			(at -2.25044 -9.6139)
			(size 0.3048 1.524)
			(layers "B.Cu" "B.Mask" "B.Paste")
			(net "XM_DATA9")
		)
		(pad "39" smd rect
			(at -1.75006 -9.6139)
			(size 0.3048 1.524)
			(layers "B.Cu" "B.Mask" "B.Paste")
			(net "XM_DATA2")
		)
		(pad "40" smd rect
			(at -1.24968 -9.6139)
			(size 0.3048 1.524)
			(layers "B.Cu" "B.Mask" "B.Paste")
			(net "XM_DATA10")
		)
		(pad "41" smd rect
			(at -0.75057 -9.6139)
			(size 0.3048 1.524)
			(layers "B.Cu" "B.Mask" "B.Paste")
			(net "XM_DATA3")
		)
		(pad "42" smd rect
			(at -0.25019 -9.6139)
			(size 0.3048 1.524)
			(layers "B.Cu" "B.Mask" "B.Paste")
			(net "XM_DATA11")
		)
		(pad "43" smd rect
			(at 0.25019 -9.6139)
			(size 0.3048 1.524)
			(layers "B.Cu" "B.Mask" "B.Paste")
			(net "P3V3")
		)
		(pad "44" smd rect
			(at 0.75057 -9.6139)
			(size 0.3048 1.524)
			(layers "B.Cu" "B.Mask" "B.Paste")
			(net "XM_DATA4")
		)
		(pad "45" smd rect
			(at 1.24968 -9.6139)
			(size 0.3048 1.524)
			(layers "B.Cu" "B.Mask" "B.Paste")
			(net "XM_DATA12")
		)
		(pad "46" smd rect
			(at 1.75006 -9.6139)
			(size 0.3048 1.524)
			(layers "B.Cu" "B.Mask" "B.Paste")
			(net "XM_DATA5")
		)
		(pad "47" smd rect
			(at 2.25044 -9.6139)
			(size 0.3048 1.524)
			(layers "B.Cu" "B.Mask" "B.Paste")
			(net "XM_DATA13")
		)
		(pad "48" smd rect
			(at 2.74955 -9.6139)
			(size 0.3048 1.524)
			(layers "B.Cu" "B.Mask" "B.Paste")
			(net "XM_DATA6")
		)
		(pad "49" smd rect
			(at 3.24993 -9.6139)
			(size 0.3048 1.524)
			(layers "B.Cu" "B.Mask" "B.Paste")
			(net "XM_DATA14")
		)
		(pad "50" smd rect
			(at 3.75031 -9.6139)
			(size 0.3048 1.524)
			(layers "B.Cu" "B.Mask" "B.Paste")
			(net "XM_DATA7")
		)
		(pad "51" smd rect
			(at 4.24942 -9.6139)
			(size 0.3048 1.524)
			(layers "B.Cu" "B.Mask" "B.Paste")
			(net "XM_DATA15")
		)
		(pad "52" smd rect
			(at 4.7498 -9.6139)
			(size 0.3048 1.524)
			(layers "B.Cu" "B.Mask" "B.Paste")
			(net "GND")
		)
		(pad "53" smd rect
			(at 5.25018 -9.6139)
			(size 0.3048 1.524)
			(layers "B.Cu" "B.Mask" "B.Paste")
			(net "EXP_BYTE_N")
		)
		(pad "54" smd rect
			(at 5.75056 -9.6139)
			(size 0.3048 1.524)
			(layers "B.Cu" "B.Mask" "B.Paste")
			(net "EXP_XM_ADDR_17")
		)
		(pad "55" smd rect
			(at 6.24967 -9.6139)
			(size 0.3048 1.524)
			(layers "B.Cu" "B.Mask" "B.Paste")
			(net "Net_770")
		)
		(pad "56" smd rect
			(at 6.75005 -9.6139)
			(size 0.3048 1.524)
			(layers "B.Cu" "B.Mask" "B.Paste")
			(net "Net_771")
		)
	)
	(footprint ""
		(layer "B.Cu")
		(at 140.2334 -87.1982)
		(property "Reference" "TP169"
			(at 0 0 0)
			(layer "B.SilkS")
			(hide yes)
			(effects
				(font
					(size 1.27 1.27)
				)
				(justify mirror)
			)
		)
		(property "Value" "TPAD28-2-GP"
			(at 0.0127 -1.6637 0)
			(unlocked yes)
			(layer "B.Fab")
			(hide yes)
			(effects
				(font
					(size 1.016 1.016)
					(thickness 0.1524)
				)
				(justify mirror)
			)
		)
		(property "Device Type" "TPAD28"
			(at 0.0127 -3.1877 0)
			(unlocked yes)
			(layer "B.Fab")
			(hide yes)
			(effects
				(font
					(size 1.016 1.016)
					(thickness 0.1524)
				)
				(justify mirror)
			)
		)
		(duplicate_pad_numbers_are_jumpers no)
		(fp_poly
			(pts
				(arc
					(start 0.3556 0)
					(mid -0.3556 0)
					(end 0.3556 0)
				)
			)
			(stroke
				(width 0)
				(type default)
			)
			(fill no)
			(layer "B.CrtYd")
		)
		(fp_poly
			(pts
				(arc
					(start 0.6096 0)
					(mid -0.6096 0)
					(end 0.6096 0)
				)
			)
			(stroke
				(width 0)
				(type default)
			)
			(fill no)
			(layer "B.Fab")
		)
		(pad "1" smd circle
			(at 0 0 180)
			(size 0.7112 0.7112)
			(layers "B.Cu" "B.Mask" "B.Paste")
			(net "EXP_I2C_SCL9")
		)
	)
)
